G04*
G04 #@! TF.GenerationSoftware,Altium Limited,Altium Designer,22.4.2 (48)*
G04*
G04 Layer_Color=8388736*
%FSLAX25Y25*%
%MOIN*%
G70*
G04*
G04 #@! TF.SameCoordinates,446674BB-F454-490D-8607-5140536C8ADF*
G04*
G04*
G04 #@! TF.FilePolarity,Positive*
G04*
G01*
G75*
%ADD13C,0.00787*%
D13*
X660532Y-241634D02*
X685138D01*
Y-213484D01*
X660532D02*
X685138D01*
X660532Y-241634D02*
Y-213484D01*
Y-262697D02*
X685138D01*
X660532Y-290846D02*
Y-262697D01*
Y-290846D02*
X685138D01*
Y-262697D01*
X38583Y8465D02*
X42126D01*
Y15157D01*
X38583D02*
X42126D01*
X38583Y8465D02*
Y15157D01*
X31693Y8465D02*
X35236D01*
Y15157D01*
X31693D02*
X35236D01*
X31693Y8465D02*
Y15157D01*
X24803Y8465D02*
X28346D01*
Y15157D01*
X24803D02*
X28346D01*
X24803Y8465D02*
Y15157D01*
X45472Y8465D02*
X49016D01*
Y15157D01*
X45472D02*
X49016D01*
X45472Y8465D02*
Y15157D01*
X80905Y-109843D02*
X84449D01*
X80905Y-116535D02*
Y-109843D01*
Y-116535D02*
X84449D01*
Y-109843D01*
X73917Y-121949D02*
X77658D01*
X73917Y-128839D02*
Y-121949D01*
Y-128839D02*
X77658D01*
Y-121949D01*
X651968Y-61761D02*
Y-56053D01*
X643307D02*
X651968D01*
X643307Y-61761D02*
Y-56053D01*
Y-61761D02*
X651968D01*
X617520Y-24360D02*
Y-18651D01*
X608858D02*
X617520D01*
X608858Y-24360D02*
Y-18651D01*
Y-24360D02*
X617520D01*
X86713Y-90009D02*
X92421D01*
X86713Y-98671D02*
Y-90009D01*
Y-98671D02*
X92421D01*
Y-90009D01*
X120177Y-71702D02*
X125886D01*
X120177Y-80364D02*
Y-71702D01*
Y-80364D02*
X125886D01*
Y-71702D01*
X480315Y-119931D02*
X492126D01*
Y-129773D02*
Y-119931D01*
X480315Y-129773D02*
X492126D01*
X480315D02*
Y-119931D01*
X510630Y-119734D02*
X520866D01*
Y-129970D02*
Y-119734D01*
X510630Y-129970D02*
X520866D01*
X510630D02*
Y-119734D01*
X454921Y-122687D02*
X466339D01*
X454921Y-128986D02*
Y-122687D01*
Y-128986D02*
X466339D01*
Y-122687D01*
M02*
